# TIMECARD (Time Appliance Project (Time Card)) — schematic netlist excerpt (pin names and nets, part order shuffled) for the footprints in the layout excerpt that follows; sources: Cadence DE-HDL packaged netlist, KiCad conversion of R4006-B0001-02_R01.brd

R108  RESISTOR  100OHM 1%  pkg SMC_0402R_H016  page 26 : \1\ = UNNAMED_14_OPTICAL_I141_A ; \2\ = UNNAMED_14_RESISTOR_I58_2
C112  CAPACITOR  0.1UF 10V 10%  pkg SMC_0402R_H022  page 14 : \1\ = XP3R3V_FPGA ; \2\ = SG

(kicad_pcb
	(version 20260206)
	(generator "pcbnew")
	(generator_version "10.0")
	(general
		(thickness 1.6)
		(legacy_teardrops no)
	)
	(paper "A4")
	(title_block
		(title "timecard-production-celestica-r4006 — R4006-B0001-02_R01.brd")
		(comment 1 "Time Appliance Project (Time Card) / footprints 777-778 of 1113")
	)
	(layers
		(0 "F.Cu" signal "TOP")
		(4 "In1.Cu" signal "L02_GND1")
		(6 "In2.Cu" signal "L03_SIG1")
		(8 "In3.Cu" signal "L04_GND2")
		(10 "In4.Cu" signal "L05_VCC1")
		(12 "In5.Cu" signal "L06_VCC2")
		(14 "In6.Cu" signal "L07_GND3")
		(16 "In7.Cu" signal "L08_SIG2")
		(18 "In8.Cu" signal "L09_GND4")
		(2 "B.Cu" signal "BOTTOM")
		(9 "F.Adhes" user "F.Adhesive")
		(11 "B.Adhes" user "B.Adhesive")
		(13 "F.Paste" user "Package Geometry/Pastemask Top")
		(15 "B.Paste" user "Package Geometry/Pastemask Bottom")
		(5 "F.SilkS" user "Ref Des/Silkscreen Top")
		(7 "B.SilkS" user "Ref Des/Silkscreen Bottom")
		(1 "F.Mask" user "Board Geometry/Soldermask Top")
		(3 "B.Mask" user "Board Geometry/Soldermask Bottom")
		(17 "Dwgs.User" user "User.Drawings")
		(19 "Cmts.User" user "User.Comments")
		(21 "Eco1.User" user "User.Eco1")
		(23 "Eco2.User" user "User.Eco2")
		(25 "Edge.Cuts" user "Board Geometry/Outline")
		(27 "Margin" user)
		(31 "F.CrtYd" user "Package Geometry/Place Bound Top")
		(29 "B.CrtYd" user "Package Geometry/Place Bound Bottom")
		(35 "F.Fab" user "Ref Des/Assembly Top")
		(33 "B.Fab" user "Ref Des/Assembly Bottom")
	)
	(footprint ""
		(layer "B.Cu")
		(at 140.97 -104.521 180)
		(property "Reference" "R108"
			(at 0.889 -3.84937 0)
			(unlocked yes)
			(layer "B.SilkS")
			(effects
				(font
					(size 0.7874 0.5842)
					(thickness 0.1524)
				)
				(justify mirror)
			)
		)
		(property "Value" "VAL*"
			(at -0.02032 2.13233 180)
			(unlocked yes)
			(layer "B.Fab")
			(hide yes)
			(effects
				(font
					(size 0.7874 0.5842)
					(thickness 0.1524)
				)
				(justify mirror)
			)
		)
		(property "Tolerance" "TOL*"
			(at -0.044704 3.05435 180)
			(unlocked yes)
			(layer "Cmts.User")
			(hide yes)
			(effects
				(font
					(size 0.7874 0.5842)
					(thickness 0.1524)
				)
				(justify mirror)
			)
		)
		(property "User Part Number" "PARTNUM*"
			(at -0.02032 4.024884 180)
			(unlocked yes)
			(layer "Cmts.User")
			(hide yes)
			(effects
				(font
					(size 0.7874 0.5842)
					(thickness 0.1524)
				)
				(justify mirror)
			)
		)
		(property "Device Type" "RESISTOR-G155-11000-01,100OHM,A"
			(at -0.008382 1.210564 180)
			(unlocked yes)
			(layer "B.Fab")
			(hide yes)
			(effects
				(font
					(size 0.7874 0.5842)
					(thickness 0.1524)
				)
				(justify mirror)
			)
		)
		(duplicate_pad_numbers_are_jumpers no)
		(fp_line
			(start 1.143 0.5588)
			(end -1.143 0.5588)
			(stroke
				(width 0.1)
				(type default)
			)
			(layer "B.SilkS")
		)
		(fp_line
			(start 1.143 -0.5588)
			(end 1.143 0.5588)
			(stroke
				(width 0.1)
				(type default)
			)
			(layer "B.SilkS")
		)
		(fp_line
			(start -1.143 0.5588)
			(end -1.143 -0.5588)
			(stroke
				(width 0.1)
				(type default)
			)
			(layer "B.SilkS")
		)
		(fp_line
			(start -1.143 -0.5588)
			(end 1.143 -0.5588)
			(stroke
				(width 0.1)
				(type default)
			)
			(layer "B.SilkS")
		)
		(fp_rect
			(start 1.143 0.5588)
			(end -1.143 -0.5588)
			(stroke
				(width 0)
				(type default)
			)
			(fill no)
			(layer "B.CrtYd")
		)
		(fp_line
			(start 0.508 0.3048)
			(end -0.508 0.3048)
			(stroke
				(width 0.1)
				(type default)
			)
			(layer "B.Fab")
		)
		(fp_line
			(start 0.508 -0.3048)
			(end 0.508 0.3048)
			(stroke
				(width 0.1)
				(type default)
			)
			(layer "B.Fab")
		)
		(fp_line
			(start -0.508 0.3048)
			(end -0.508 -0.3048)
			(stroke
				(width 0.1)
				(type default)
			)
			(layer "B.Fab")
		)
		(fp_line
			(start -0.508 -0.3048)
			(end 0.508 -0.3048)
			(stroke
				(width 0.1)
				(type default)
			)
			(layer "B.Fab")
		)
		(pad "1" smd rect
			(at 0.5334 0)
			(size 0.7112 0.6096)
			(layers "B.Cu" "B.Mask" "B.Paste")
			(net "UNNAMED_14_OPTICAL_I141_A")
		)
		(pad "2" smd rect
			(at -0.5334 0)
			(size 0.7112 0.6096)
			(layers "B.Cu" "B.Mask" "B.Paste")
			(net "UNNAMED_14_RESISTOR_I58_2")
		)
		(zone
			(layer "B.Cu")
			(hatch none 0.5)
			(connect_pads
				(clearance 0)
			)
			(min_thickness 0.25)
			(keepout
				(tracks allowed)
				(vias not_allowed)
				(pads allowed)
				(copperpour not_allowed)
				(footprints allowed)
			)
			(placement
				(enabled no)
				(sheetname "")
			)
			(fill
				(thermal_gap 0.5)
				(thermal_bridge_width 0.5)
				(island_removal_mode 0)
			)
			(polygon
				(pts
					(xy 140.8938 -104.8258) (xy 140.8938 -104.2162) (xy 141.0462 -104.2162) (xy 141.0462 -104.8258)
				)
			)
		)
	)
	(footprint ""
		(layer "B.Cu")
		(at 105.347262 -51.823112 180)
		(property "Reference" "C112"
			(at -0.824738 0.977138 0)
			(unlocked yes)
			(layer "B.SilkS")
			(effects
				(font
					(size 0.635 0.4064)
					(thickness 0.1524)
				)
				(justify mirror)
			)
		)
		(property "Value" "VAL*"
			(at 0 3.718306 180)
			(unlocked yes)
			(layer "B.Fab")
			(hide yes)
			(effects
				(font
					(size 0.7874 0.5842)
					(thickness 0.127)
				)
				(justify mirror)
			)
		)
		(property "Device Type" "CAPACITOR-G105-0B104-CK,0.1UF,A"
			(at 0 1.432306 180)
			(unlocked yes)
			(layer "B.Fab")
			(hide yes)
			(effects
				(font
					(size 0.7874 0.5842)
					(thickness 0.127)
				)
				(justify mirror)
			)
		)
		(property "User Part Number" "PARTNUM*"
			(at 0 2.575306 180)
			(unlocked yes)
			(layer "Cmts.User")
			(hide yes)
			(effects
				(font
					(size 0.7874 0.5842)
					(thickness 0.127)
				)
				(justify mirror)
			)
		)
		(property "Tolerance" "TOL*"
			(at 0 4.861306 180)
			(unlocked yes)
			(layer "Cmts.User")
			(hide yes)
			(effects
				(font
					(size 0.7874 0.5842)
					(thickness 0.127)
				)
				(justify mirror)
			)
		)
		(duplicate_pad_numbers_are_jumpers no)
		(fp_line
			(start 0.970026 0.4699)
			(end 0.970026 -0.4699)
			(stroke
				(width 0.1)
				(type default)
			)
			(layer "B.SilkS")
		)
		(fp_line
			(start 0.970026 -0.4699)
			(end -0.970026 -0.4699)
			(stroke
				(width 0.1)
				(type default)
			)
			(layer "B.SilkS")
		)
		(fp_line
			(start -0.970026 0.4699)
			(end 0.970026 0.4699)
			(stroke
				(width 0.1)
				(type default)
			)
			(layer "B.SilkS")
		)
		(fp_line
			(start -0.970026 -0.4699)
			(end -0.970026 0.4699)
			(stroke
				(width 0.1)
				(type default)
			)
			(layer "B.SilkS")
		)
		(fp_poly
			(pts
				(xy 0.970026 0.4699) (xy -0.970026 0.4699) (xy -0.970026 -0.4699) (xy 0.970026 -0.4699)
			)
			(stroke
				(width 0)
				(type default)
			)
			(fill no)
			(layer "B.CrtYd")
		)
		(fp_line
			(start 0.508 0.3048)
			(end 0.508 -0.3048)
			(stroke
				(width 0.1)
				(type default)
			)
			(layer "B.Fab")
		)
		(fp_line
			(start 0.508 -0.3048)
			(end -0.508 -0.3048)
			(stroke
				(width 0.1)
				(type default)
			)
			(layer "B.Fab")
		)
		(fp_line
			(start -0.508 0.3048)
			(end 0.508 0.3048)
			(stroke
				(width 0.1)
				(type default)
			)
			(layer "B.Fab")
		)
		(fp_line
			(start -0.508 -0.3048)
			(end -0.508 0.3048)
			(stroke
				(width 0.1)
				(type default)
			)
			(layer "B.Fab")
		)
		(pad "1" smd circle
			(at 0.500126 0)
			(size 0.635 0.635)
			(layers "B.Cu" "B.Mask" "B.Paste")
			(net "XP3R3V_FPGA")
		)
		(pad "2" smd circle
			(at -0.500126 0)
			(size 0.635 0.635)
			(layers "B.Cu" "B.Mask" "B.Paste")
			(net "SG")
		)
	)
)
